(kicad_pcb
	(version 20260206)
	(generator "pcbnew")
	(generator_version "10.0")
	(general
		(thickness 1.6)
		(legacy_teardrops no)
	)
	(paper "A4")
	(title_block
		(title "04192023_DAF0TMB3IC0_F0TG_MB_C_brd_V02_OCP.brd")
		(comment 1 "Grand Teton / footprints 7973-7978 of 8354")
	)
	(layers
		(0 "F.Cu" signal "TOP")
		(4 "In1.Cu" signal "GND")
		(6 "In2.Cu" signal "IN1")
		(8 "In3.Cu" signal "GND1")
		(10 "In4.Cu" signal "IN2")
		(12 "In5.Cu" signal "GND2")
		(14 "In6.Cu" signal "IN3")
		(16 "In7.Cu" signal "GND3")
		(18 "In8.Cu" signal "VCC")
		(20 "In9.Cu" signal "VCC1")
		(22 "In10.Cu" signal "GND4")
		(24 "In11.Cu" signal "IN4")
		(26 "In12.Cu" signal "GND5")
		(28 "In13.Cu" signal "IN5")
		(30 "In14.Cu" signal "GND6")
		(32 "In15.Cu" signal "IN6")
		(34 "In16.Cu" signal "GND7")
		(2 "B.Cu" signal "BOTTOM")
		(9 "F.Adhes" user "F.Adhesive")
		(11 "B.Adhes" user "B.Adhesive")
		(13 "F.Paste" user "Package Geometry/Pastemask Top")
		(15 "B.Paste" user "Package Geometry/Pastemask Bottom")
		(5 "F.SilkS" user "Ref Des/Silkscreen Top")
		(7 "B.SilkS" user "Ref Des/Silkscreen Bottom")
		(1 "F.Mask" user "Board Geometry/Soldermask Top")
		(3 "B.Mask" user "Board Geometry/Soldermask Bottom")
		(17 "Dwgs.User" user "User.Drawings")
		(19 "Cmts.User" user "User.Comments")
		(21 "Eco1.User" user "User.Eco1")
		(23 "Eco2.User" user "User.Eco2")
		(25 "Edge.Cuts" user "Board Geometry/Outline")
		(27 "Margin" user)
		(31 "F.CrtYd" user "Package Geometry/Place Bound Top")
		(29 "B.CrtYd" user "Package Geometry/Place Bound Bottom")
		(35 "F.Fab" user "Ref Des/Assembly Top")
		(33 "B.Fab" user "Ref Des/Assembly Bottom")
	)
	(footprint ""
		(layer "B.Cu")
		(at 399.522696 -341.172292 90)
		(property "Reference" "R941"
			(at 0 0 90)
			(layer "B.SilkS")
			(hide yes)
			(effects
				(font
					(size 1.27 1.27)
				)
				(justify mirror)
			)
		)
		(property "Value" ""
			(at 0 0 90)
			(layer "B.Fab")
			(effects
				(font
					(size 1.27 1.27)
				)
				(justify mirror)
			)
		)
		(duplicate_pad_numbers_are_jumpers no)
		(fp_line
			(start 0.7874 -0.4064)
			(end -0.7874 -0.4064)
			(stroke
				(width 0.1524)
				(type default)
			)
			(layer "B.SilkS")
		)
		(fp_line
			(start -0.7874 -0.4064)
			(end -0.7874 0.4064)
			(stroke
				(width 0.1524)
				(type default)
			)
			(layer "B.SilkS")
		)
		(fp_line
			(start 0.7874 0.4064)
			(end 0.7874 -0.4064)
			(stroke
				(width 0.1524)
				(type default)
			)
			(layer "B.SilkS")
		)
		(fp_line
			(start -0.7874 0.4064)
			(end 0.7874 0.4064)
			(stroke
				(width 0.1524)
				(type default)
			)
			(layer "B.SilkS")
		)
		(fp_line
			(start 0.67945 -0.305054)
			(end 0.12065 -0.305054)
			(stroke
				(width 0.1)
				(type default)
			)
			(layer "B.Fab")
		)
		(fp_line
			(start 0.12065 -0.305054)
			(end 0.12065 -0.2794)
			(stroke
				(width 0.1)
				(type default)
			)
			(layer "B.Fab")
		)
		(fp_line
			(start -0.12065 -0.3048)
			(end -0.67945 -0.3048)
			(stroke
				(width 0.1)
				(type default)
			)
			(layer "B.Fab")
		)
		(fp_line
			(start -0.67945 -0.3048)
			(end -0.67945 0.3048)
			(stroke
				(width 0.1)
				(type default)
			)
			(layer "B.Fab")
		)
		(fp_line
			(start 0.12065 -0.2794)
			(end -0.12065 -0.2794)
			(stroke
				(width 0.1)
				(type default)
			)
			(layer "B.Fab")
		)
		(fp_line
			(start -0.12065 -0.2794)
			(end -0.12065 -0.3048)
			(stroke
				(width 0.1)
				(type default)
			)
			(layer "B.Fab")
		)
		(fp_line
			(start 0.12065 0.2794)
			(end 0.12065 0.3048)
			(stroke
				(width 0.1)
				(type default)
			)
			(layer "B.Fab")
		)
		(fp_line
			(start -0.120396 0.2794)
			(end 0.12065 0.2794)
			(stroke
				(width 0.1)
				(type default)
			)
			(layer "B.Fab")
		)
		(fp_line
			(start 0.67945 0.3048)
			(end 0.67945 -0.305054)
			(stroke
				(width 0.1)
				(type default)
			)
			(layer "B.Fab")
		)
		(fp_line
			(start 0.12065 0.3048)
			(end 0.67945 0.3048)
			(stroke
				(width 0.1)
				(type default)
			)
			(layer "B.Fab")
		)
		(fp_line
			(start -0.120396 0.3048)
			(end -0.120396 0.2794)
			(stroke
				(width 0.1)
				(type default)
			)
			(layer "B.Fab")
		)
		(fp_line
			(start -0.67945 0.3048)
			(end -0.120396 0.3048)
			(stroke
				(width 0.1)
				(type default)
			)
			(layer "B.Fab")
		)
		(pad "1" smd circle
			(at 0.40005 0 270)
			(size 0 0)
			(layers "B.Cu" "B.Mask" "B.Paste")
			(net "BOOT_RDY_H")
		)
		(pad "2" smd circle
			(at -0.40005 0 270)
			(size 0 0)
			(layers "B.Cu" "B.Mask" "B.Paste")
			(net "BOOT_RDY_R1_N")
		)
	)
	(footprint ""
		(layer "B.Cu")
		(at 371.551454 -254.19431)
		(property "Reference" "C2579"
			(at 0 0 0)
			(layer "B.SilkS")
			(hide yes)
			(effects
				(font
					(size 1.27 1.27)
				)
				(justify mirror)
			)
		)
		(property "Value" ""
			(at 0 0 0)
			(layer "B.Fab")
			(effects
				(font
					(size 1.27 1.27)
				)
				(justify mirror)
			)
		)
		(duplicate_pad_numbers_are_jumpers no)
		(fp_line
			(start -0.7874 -0.4064)
			(end -0.7874 0.4064)
			(stroke
				(width 0.1524)
				(type default)
			)
			(layer "B.SilkS")
		)
		(fp_line
			(start -0.7874 0.4064)
			(end 0.7874 0.4064)
			(stroke
				(width 0.1524)
				(type default)
			)
			(layer "B.SilkS")
		)
		(fp_line
			(start 0.7874 -0.4064)
			(end -0.7874 -0.4064)
			(stroke
				(width 0.1524)
				(type default)
			)
			(layer "B.SilkS")
		)
		(fp_line
			(start 0.7874 0.4064)
			(end 0.7874 -0.4064)
			(stroke
				(width 0.1524)
				(type default)
			)
			(layer "B.SilkS")
		)
		(fp_line
			(start -0.67945 -0.3048)
			(end -0.67945 0.3048)
			(stroke
				(width 0.1)
				(type default)
			)
			(layer "B.Fab")
		)
		(fp_line
			(start -0.67945 0.3048)
			(end -0.120396 0.3048)
			(stroke
				(width 0.1)
				(type default)
			)
			(layer "B.Fab")
		)
		(fp_line
			(start -0.12065 -0.3048)
			(end -0.67945 -0.3048)
			(stroke
				(width 0.1)
				(type default)
			)
			(layer "B.Fab")
		)
		(fp_line
			(start -0.12065 -0.2794)
			(end -0.12065 -0.3048)
			(stroke
				(width 0.1)
				(type default)
			)
			(layer "B.Fab")
		)
		(fp_line
			(start -0.120396 0.2794)
			(end 0.12065 0.2794)
			(stroke
				(width 0.1)
				(type default)
			)
			(layer "B.Fab")
		)
		(fp_line
			(start -0.120396 0.3048)
			(end -0.120396 0.2794)
			(stroke
				(width 0.1)
				(type default)
			)
			(layer "B.Fab")
		)
		(fp_line
			(start 0.12065 -0.305054)
			(end 0.12065 -0.2794)
			(stroke
				(width 0.1)
				(type default)
			)
			(layer "B.Fab")
		)
		(fp_line
			(start 0.12065 -0.2794)
			(end -0.12065 -0.2794)
			(stroke
				(width 0.1)
				(type default)
			)
			(layer "B.Fab")
		)
		(fp_line
			(start 0.12065 0.2794)
			(end 0.12065 0.3048)
			(stroke
				(width 0.1)
				(type default)
			)
			(layer "B.Fab")
		)
		(fp_line
			(start 0.12065 0.3048)
			(end 0.67945 0.3048)
			(stroke
				(width 0.1)
				(type default)
			)
			(layer "B.Fab")
		)
		(fp_line
			(start 0.67945 -0.305054)
			(end 0.12065 -0.305054)
			(stroke
				(width 0.1)
				(type default)
			)
			(layer "B.Fab")
		)
		(fp_line
			(start 0.67945 0.3048)
			(end 0.67945 -0.305054)
			(stroke
				(width 0.1)
				(type default)
			)
			(layer "B.Fab")
		)
		(pad "1" smd circle
			(at 0.40005 0 180)
			(size 0 0)
			(layers "B.Cu" "B.Mask" "B.Paste")
			(net "PVDDCR_SOC_P0")
		)
		(pad "2" smd circle
			(at -0.40005 0 180)
			(size 0 0)
			(layers "B.Cu" "B.Mask" "B.Paste")
			(net "GND")
		)
	)
	(footprint ""
		(layer "B.Cu")
		(at 293.277036 -244.08511 180)
		(property "Reference" "R377"
			(at 0 0 0)
			(layer "B.SilkS")
			(hide yes)
			(effects
				(font
					(size 1.27 1.27)
				)
				(justify mirror)
			)
		)
		(property "Value" ""
			(at 0 0 0)
			(layer "B.Fab")
			(effects
				(font
					(size 1.27 1.27)
				)
				(justify mirror)
			)
		)
		(duplicate_pad_numbers_are_jumpers no)
		(fp_line
			(start 0.7874 0.4064)
			(end 0.7874 -0.4064)
			(stroke
				(width 0.1524)
				(type default)
			)
			(layer "B.SilkS")
		)
		(fp_line
			(start 0.7874 -0.4064)
			(end -0.7874 -0.4064)
			(stroke
				(width 0.1524)
				(type default)
			)
			(layer "B.SilkS")
		)
		(fp_line
			(start -0.7874 0.4064)
			(end 0.7874 0.4064)
			(stroke
				(width 0.1524)
				(type default)
			)
			(layer "B.SilkS")
		)
		(fp_line
			(start -0.7874 -0.4064)
			(end -0.7874 0.4064)
			(stroke
				(width 0.1524)
				(type default)
			)
			(layer "B.SilkS")
		)
		(fp_line
			(start 0.67945 0.3048)
			(end 0.67945 -0.305054)
			(stroke
				(width 0.1)
				(type default)
			)
			(layer "B.Fab")
		)
		(fp_line
			(start 0.67945 -0.305054)
			(end 0.12065 -0.305054)
			(stroke
				(width 0.1)
				(type default)
			)
			(layer "B.Fab")
		)
		(fp_line
			(start 0.12065 0.3048)
			(end 0.67945 0.3048)
			(stroke
				(width 0.1)
				(type default)
			)
			(layer "B.Fab")
		)
		(fp_line
			(start 0.12065 0.2794)
			(end 0.12065 0.3048)
			(stroke
				(width 0.1)
				(type default)
			)
			(layer "B.Fab")
		)
		(fp_line
			(start 0.12065 -0.2794)
			(end -0.12065 -0.2794)
			(stroke
				(width 0.1)
				(type default)
			)
			(layer "B.Fab")
		)
		(fp_line
			(start 0.12065 -0.305054)
			(end 0.12065 -0.2794)
			(stroke
				(width 0.1)
				(type default)
			)
			(layer "B.Fab")
		)
		(fp_line
			(start -0.120396 0.3048)
			(end -0.120396 0.2794)
			(stroke
				(width 0.1)
				(type default)
			)
			(layer "B.Fab")
		)
		(fp_line
			(start -0.120396 0.2794)
			(end 0.12065 0.2794)
			(stroke
				(width 0.1)
				(type default)
			)
			(layer "B.Fab")
		)
		(fp_line
			(start -0.12065 -0.2794)
			(end -0.12065 -0.3048)
			(stroke
				(width 0.1)
				(type default)
			)
			(layer "B.Fab")
		)
		(fp_line
			(start -0.12065 -0.3048)
			(end -0.67945 -0.3048)
			(stroke
				(width 0.1)
				(type default)
			)
			(layer "B.Fab")
		)
		(fp_line
			(start -0.67945 0.3048)
			(end -0.120396 0.3048)
			(stroke
				(width 0.1)
				(type default)
			)
			(layer "B.Fab")
		)
		(fp_line
			(start -0.67945 -0.3048)
			(end -0.67945 0.3048)
			(stroke
				(width 0.1)
				(type default)
			)
			(layer "B.Fab")
		)
		(pad "1" smd circle
			(at 0.40005 0)
			(size 0 0)
			(layers "B.Cu" "B.Mask" "B.Paste")
			(net "M_C_CPU0_ALERT_N")
		)
		(pad "2" smd circle
			(at -0.40005 0)
			(size 0 0)
			(layers "B.Cu" "B.Mask" "B.Paste")
			(net "M_C_CPU0_ALERT_R_N")
		)
	)
	(footprint ""
		(layer "B.Cu")
		(at 150.988776 -17.693894 -90)
		(property "Reference" "R2212"
			(at 0 0 90)
			(layer "B.SilkS")
			(hide yes)
			(effects
				(font
					(size 1.27 1.27)
				)
				(justify mirror)
			)
		)
		(property "Value" ""
			(at 0 0 90)
			(layer "B.Fab")
			(effects
				(font
					(size 1.27 1.27)
				)
				(justify mirror)
			)
		)
		(duplicate_pad_numbers_are_jumpers no)
		(fp_line
			(start -0.7874 0.4064)
			(end 0.7874 0.4064)
			(stroke
				(width 0.1524)
				(type default)
			)
			(layer "B.SilkS")
		)
		(fp_line
			(start 0.7874 0.4064)
			(end 0.7874 -0.4064)
			(stroke
				(width 0.1524)
				(type default)
			)
			(layer "B.SilkS")
		)
		(fp_line
			(start -0.7874 -0.4064)
			(end -0.7874 0.4064)
			(stroke
				(width 0.1524)
				(type default)
			)
			(layer "B.SilkS")
		)
		(fp_line
			(start 0.7874 -0.4064)
			(end -0.7874 -0.4064)
			(stroke
				(width 0.1524)
				(type default)
			)
			(layer "B.SilkS")
		)
		(fp_line
			(start -0.67945 0.3048)
			(end -0.120396 0.3048)
			(stroke
				(width 0.1)
				(type default)
			)
			(layer "B.Fab")
		)
		(fp_line
			(start -0.120396 0.3048)
			(end -0.120396 0.2794)
			(stroke
				(width 0.1)
				(type default)
			)
			(layer "B.Fab")
		)
		(fp_line
			(start 0.12065 0.3048)
			(end 0.67945 0.3048)
			(stroke
				(width 0.1)
				(type default)
			)
			(layer "B.Fab")
		)
		(fp_line
			(start 0.67945 0.3048)
			(end 0.67945 -0.305054)
			(stroke
				(width 0.1)
				(type default)
			)
			(layer "B.Fab")
		)
		(fp_line
			(start -0.120396 0.2794)
			(end 0.12065 0.2794)
			(stroke
				(width 0.1)
				(type default)
			)
			(layer "B.Fab")
		)
		(fp_line
			(start 0.12065 0.2794)
			(end 0.12065 0.3048)
			(stroke
				(width 0.1)
				(type default)
			)
			(layer "B.Fab")
		)
		(fp_line
			(start -0.12065 -0.2794)
			(end -0.12065 -0.3048)
			(stroke
				(width 0.1)
				(type default)
			)
			(layer "B.Fab")
		)
		(fp_line
			(start 0.12065 -0.2794)
			(end -0.12065 -0.2794)
			(stroke
				(width 0.1)
				(type default)
			)
			(layer "B.Fab")
		)
		(fp_line
			(start -0.67945 -0.3048)
			(end -0.67945 0.3048)
			(stroke
				(width 0.1)
				(type default)
			)
			(layer "B.Fab")
		)
		(fp_line
			(start -0.12065 -0.3048)
			(end -0.67945 -0.3048)
			(stroke
				(width 0.1)
				(type default)
			)
			(layer "B.Fab")
		)
		(fp_line
			(start 0.12065 -0.305054)
			(end 0.12065 -0.2794)
			(stroke
				(width 0.1)
				(type default)
			)
			(layer "B.Fab")
		)
		(fp_line
			(start 0.67945 -0.305054)
			(end 0.12065 -0.305054)
			(stroke
				(width 0.1)
				(type default)
			)
			(layer "B.Fab")
		)
		(pad "1" smd circle
			(at 0.40005 0 90)
			(size 0 0)
			(layers "B.Cu" "B.Mask" "B.Paste")
			(net "SMB_HOST_CLK_3V3AUX_SCL")
		)
		(pad "2" smd circle
			(at -0.40005 0 90)
			(size 0 0)
			(layers "B.Cu" "B.Mask" "B.Paste")
			(net "P3V3_AUX")
		)
	)
	(footprint ""
		(layer "B.Cu")
		(at 340.891876 -66.708782 90)
		(property "Reference" "R3096"
			(at 0 0 90)
			(layer "B.SilkS")
			(hide yes)
			(effects
				(font
					(size 1.27 1.27)
				)
				(justify mirror)
			)
		)
		(property "Value" ""
			(at 0 0 90)
			(layer "B.Fab")
			(effects
				(font
					(size 1.27 1.27)
				)
				(justify mirror)
			)
		)
		(duplicate_pad_numbers_are_jumpers no)
		(fp_line
			(start 0.7874 -0.4064)
			(end -0.7874 -0.4064)
			(stroke
				(width 0.1524)
				(type default)
			)
			(layer "B.SilkS")
		)
		(fp_line
			(start -0.7874 -0.4064)
			(end -0.7874 0.4064)
			(stroke
				(width 0.1524)
				(type default)
			)
			(layer "B.SilkS")
		)
		(fp_line
			(start 0.7874 0.4064)
			(end 0.7874 -0.4064)
			(stroke
				(width 0.1524)
				(type default)
			)
			(layer "B.SilkS")
		)
		(fp_line
			(start -0.7874 0.4064)
			(end 0.7874 0.4064)
			(stroke
				(width 0.1524)
				(type default)
			)
			(layer "B.SilkS")
		)
		(fp_line
			(start 0.67945 -0.305054)
			(end 0.12065 -0.305054)
			(stroke
				(width 0.1)
				(type default)
			)
			(layer "B.Fab")
		)
		(fp_line
			(start 0.12065 -0.305054)
			(end 0.12065 -0.2794)
			(stroke
				(width 0.1)
				(type default)
			)
			(layer "B.Fab")
		)
		(fp_line
			(start -0.12065 -0.3048)
			(end -0.67945 -0.3048)
			(stroke
				(width 0.1)
				(type default)
			)
			(layer "B.Fab")
		)
		(fp_line
			(start -0.67945 -0.3048)
			(end -0.67945 0.3048)
			(stroke
				(width 0.1)
				(type default)
			)
			(layer "B.Fab")
		)
		(fp_line
			(start 0.12065 -0.2794)
			(end -0.12065 -0.2794)
			(stroke
				(width 0.1)
				(type default)
			)
			(layer "B.Fab")
		)
		(fp_line
			(start -0.12065 -0.2794)
			(end -0.12065 -0.3048)
			(stroke
				(width 0.1)
				(type default)
			)
			(layer "B.Fab")
		)
		(fp_line
			(start 0.12065 0.2794)
			(end 0.12065 0.3048)
			(stroke
				(width 0.1)
				(type default)
			)
			(layer "B.Fab")
		)
		(fp_line
			(start -0.120396 0.2794)
			(end 0.12065 0.2794)
			(stroke
				(width 0.1)
				(type default)
			)
			(layer "B.Fab")
		)
		(fp_line
			(start 0.67945 0.3048)
			(end 0.67945 -0.305054)
			(stroke
				(width 0.1)
				(type default)
			)
			(layer "B.Fab")
		)
		(fp_line
			(start 0.12065 0.3048)
			(end 0.67945 0.3048)
			(stroke
				(width 0.1)
				(type default)
			)
			(layer "B.Fab")
		)
		(fp_line
			(start -0.120396 0.3048)
			(end -0.120396 0.2794)
			(stroke
				(width 0.1)
				(type default)
			)
			(layer "B.Fab")
		)
		(fp_line
			(start -0.67945 0.3048)
			(end -0.120396 0.3048)
			(stroke
				(width 0.1)
				(type default)
			)
			(layer "B.Fab")
		)
		(pad "1" smd circle
			(at 0.40005 0 270)
			(size 0 0)
			(layers "B.Cu" "B.Mask" "B.Paste")
			(net "LED_PWRGD_PVDDCR_CPU1_P1_R")
		)
		(pad "2" smd circle
			(at -0.40005 0 270)
			(size 0 0)
			(layers "B.Cu" "B.Mask" "B.Paste")
			(net "P3V3_AUX")
		)
	)
	(footprint ""
		(layer "B.Cu")
		(at 194.945 -100.294948 -90)
		(property "Reference" "R267"
			(at 0 0 90)
			(layer "B.SilkS")
			(hide yes)
			(effects
				(font
					(size 1.27 1.27)
				)
				(justify mirror)
			)
		)
		(property "Value" ""
			(at 0 0 90)
			(layer "B.Fab")
			(effects
				(font
					(size 1.27 1.27)
				)
				(justify mirror)
			)
		)
		(duplicate_pad_numbers_are_jumpers no)
		(fp_line
			(start -0.7874 0.4064)
			(end 0.7874 0.4064)
			(stroke
				(width 0.1524)
				(type default)
			)
			(layer "B.SilkS")
		)
		(fp_line
			(start 0.7874 0.4064)
			(end 0.7874 -0.4064)
			(stroke
				(width 0.1524)
				(type default)
			)
			(layer "B.SilkS")
		)
		(fp_line
			(start -0.7874 -0.4064)
			(end -0.7874 0.4064)
			(stroke
				(width 0.1524)
				(type default)
			)
			(layer "B.SilkS")
		)
		(fp_line
			(start 0.7874 -0.4064)
			(end -0.7874 -0.4064)
			(stroke
				(width 0.1524)
				(type default)
			)
			(layer "B.SilkS")
		)
		(fp_line
			(start -0.67945 0.3048)
			(end -0.120396 0.3048)
			(stroke
				(width 0.1)
				(type default)
			)
			(layer "B.Fab")
		)
		(fp_line
			(start -0.120396 0.3048)
			(end -0.120396 0.2794)
			(stroke
				(width 0.1)
				(type default)
			)
			(layer "B.Fab")
		)
		(fp_line
			(start 0.12065 0.3048)
			(end 0.67945 0.3048)
			(stroke
				(width 0.1)
				(type default)
			)
			(layer "B.Fab")
		)
		(fp_line
			(start 0.67945 0.3048)
			(end 0.67945 -0.305054)
			(stroke
				(width 0.1)
				(type default)
			)
			(layer "B.Fab")
		)
		(fp_line
			(start -0.120396 0.2794)
			(end 0.12065 0.2794)
			(stroke
				(width 0.1)
				(type default)
			)
			(layer "B.Fab")
		)
		(fp_line
			(start 0.12065 0.2794)
			(end 0.12065 0.3048)
			(stroke
				(width 0.1)
				(type default)
			)
			(layer "B.Fab")
		)
		(fp_line
			(start -0.12065 -0.2794)
			(end -0.12065 -0.3048)
			(stroke
				(width 0.1)
				(type default)
			)
			(layer "B.Fab")
		)
		(fp_line
			(start 0.12065 -0.2794)
			(end -0.12065 -0.2794)
			(stroke
				(width 0.1)
				(type default)
			)
			(layer "B.Fab")
		)
		(fp_line
			(start -0.67945 -0.3048)
			(end -0.67945 0.3048)
			(stroke
				(width 0.1)
				(type default)
			)
			(layer "B.Fab")
		)
		(fp_line
			(start -0.12065 -0.3048)
			(end -0.67945 -0.3048)
			(stroke
				(width 0.1)
				(type default)
			)
			(layer "B.Fab")
		)
		(fp_line
			(start 0.12065 -0.305054)
			(end 0.12065 -0.2794)
			(stroke
				(width 0.1)
				(type default)
			)
			(layer "B.Fab")
		)
		(fp_line
			(start 0.67945 -0.305054)
			(end 0.12065 -0.305054)
			(stroke
				(width 0.1)
				(type default)
			)
			(layer "B.Fab")
		)
		(pad "1" smd circle
			(at 0.40005 0 90)
			(size 0 0)
			(layers "B.Cu" "B.Mask" "B.Paste")
			(net "CPU1_SA1")
		)
		(pad "2" smd circle
			(at -0.40005 0 90)
			(size 0 0)
			(layers "B.Cu" "B.Mask" "B.Paste")
			(net "FM_CPU1_SA1")
		)
	)
)
